(kicad_pcb
	(version 20260206)
	(generator "pcbnew")
	(generator_version "10.0")
	(general
		(thickness 1.6)
		(legacy_teardrops no)
	)
	(paper "A4")
	(title_block
		(title "03242023_DA0F0TMBIJ0_F0T_Motherboard_J_brd_V01_OCP.brd")
		(comment 1 "Grand Teton / footprints 245-246 of 6105")
	)
	(layers
		(0 "F.Cu" signal "TOP")
		(4 "In1.Cu" signal "GND")
		(6 "In2.Cu" signal "IN1")
		(8 "In3.Cu" signal "GND1")
		(10 "In4.Cu" signal "IN2")
		(12 "In5.Cu" signal "GND2")
		(14 "In6.Cu" signal "IN3")
		(16 "In7.Cu" signal "GND3")
		(18 "In8.Cu" signal "VCC")
		(20 "In9.Cu" signal "VCC1")
		(22 "In10.Cu" signal "GND4")
		(24 "In11.Cu" signal "IN4")
		(26 "In12.Cu" signal "GND5")
		(28 "In13.Cu" signal "IN5")
		(30 "In14.Cu" signal "GND6")
		(32 "In15.Cu" signal "IN6")
		(34 "In16.Cu" signal "GND7")
		(2 "B.Cu" signal "BOTTOM")
		(9 "F.Adhes" user "F.Adhesive")
		(11 "B.Adhes" user "B.Adhesive")
		(13 "F.Paste" user "Package Geometry/Pastemask Top")
		(15 "B.Paste" user "Package Geometry/Pastemask Bottom")
		(5 "F.SilkS" user "Ref Des/Silkscreen Top")
		(7 "B.SilkS" user "Ref Des/Silkscreen Bottom")
		(1 "F.Mask" user "Board Geometry/Soldermask Top")
		(3 "B.Mask" user "Board Geometry/Soldermask Bottom")
		(17 "Dwgs.User" user "User.Drawings")
		(19 "Cmts.User" user "User.Comments")
		(21 "Eco1.User" user "User.Eco1")
		(23 "Eco2.User" user "User.Eco2")
		(25 "Edge.Cuts" user "Board Geometry/Outline")
		(27 "Margin" user)
		(31 "F.CrtYd" user "Package Geometry/Place Bound Top")
		(29 "B.CrtYd" user "Package Geometry/Place Bound Bottom")
		(35 "F.Fab" user "Ref Des/Assembly Top")
		(33 "B.Fab" user "Ref Des/Assembly Bottom")
	)
	(footprint ""
		(layer "F.Cu")
		(at 27.662886 -164.827204 -90)
		(property "Reference" "PU18"
			(at -0.638048 -8.11022 0)
			(unlocked yes)
			(layer "F.SilkS")
			(effects
				(font
					(size 0.7874 0.5842)
					(thickness 0.1524)
				)
			)
		)
		(property "Value" ""
			(at 0 0 270)
			(layer "F.Fab")
			(effects
				(font
					(size 1.27 1.27)
				)
			)
		)
		(duplicate_pad_numbers_are_jumpers no)
		(fp_line
			(start 1.778 3.6322)
			(end 1.778 2.8702)
			(stroke
				(width 0.1524)
				(type default)
			)
			(layer "F.SilkS")
		)
		(fp_line
			(start -0.2032 2.8829)
			(end -0.2032 3.2639)
			(stroke
				(width 0.1524)
				(type default)
			)
			(layer "F.SilkS")
		)
		(fp_line
			(start -2.500122 2.500122)
			(end -2.500122 2.018538)
			(stroke
				(width 0.1524)
				(type default)
			)
			(layer "F.SilkS")
		)
		(fp_line
			(start -2.015998 2.500122)
			(end -2.500122 2.500122)
			(stroke
				(width 0.1524)
				(type default)
			)
			(layer "F.SilkS")
		)
		(fp_line
			(start 2.500122 2.500122)
			(end 2.015998 2.500122)
			(stroke
				(width 0.1524)
				(type default)
			)
			(layer "F.SilkS")
		)
		(fp_line
			(start 2.500122 2.015998)
			(end 2.500122 2.500122)
			(stroke
				(width 0.1524)
				(type default)
			)
			(layer "F.SilkS")
		)
		(fp_line
			(start -3.6576 1.8034)
			(end -2.8956 1.8034)
			(stroke
				(width 0.1524)
				(type default)
			)
			(layer "F.SilkS")
		)
		(fp_line
			(start 2.8829 0.2032)
			(end 3.2639 0.2032)
			(stroke
				(width 0.1524)
				(type default)
			)
			(layer "F.SilkS")
		)
		(fp_line
			(start -3.2639 -0.1778)
			(end -2.8829 -0.1778)
			(stroke
				(width 0.1524)
				(type default)
			)
			(layer "F.SilkS")
		)
		(fp_line
			(start 2.8702 -1.778)
			(end 3.6322 -1.778)
			(stroke
				(width 0.1524)
				(type default)
			)
			(layer "F.SilkS")
		)
		(fp_line
			(start -2.500122 -2.015998)
			(end -2.500122 -2.500122)
			(stroke
				(width 0.1524)
				(type default)
			)
			(layer "F.SilkS")
		)
		(fp_line
			(start -2.500122 -2.500122)
			(end -2.015998 -2.500122)
			(stroke
				(width 0.1524)
				(type default)
			)
			(layer "F.SilkS")
		)
		(fp_line
			(start 2.015998 -2.500122)
			(end 2.500122 -2.500122)
			(stroke
				(width 0.1524)
				(type default)
			)
			(layer "F.SilkS")
		)
		(fp_line
			(start 2.500122 -2.500122)
			(end 2.500122 -2.015998)
			(stroke
				(width 0.1524)
				(type default)
			)
			(layer "F.SilkS")
		)
		(fp_line
			(start -1.8034 -2.8702)
			(end -1.8034 -3.6322)
			(stroke
				(width 0.1524)
				(type default)
			)
			(layer "F.SilkS")
		)
		(fp_line
			(start 0.1778 -3.2385)
			(end 0.1778 -2.8575)
			(stroke
				(width 0.1524)
				(type default)
			)
			(layer "F.SilkS")
		)
		(fp_poly
			(pts
				(xy -3.295142 -2.36601) (xy -2.882646 -2.778506) (xy -2.676398 -2.160016)
			)
			(stroke
				(width 0)
				(type default)
			)
			(fill yes)
			(layer "F.SilkS")
		)
		(fp_line
			(start 1.778 3.6322)
			(end 1.778 2.8702)
			(stroke
				(width 0.1)
				(type default)
			)
			(layer "F.Fab")
		)
		(fp_line
			(start -0.2032 2.8829)
			(end -0.2032 3.2639)
			(stroke
				(width 0.1)
				(type default)
			)
			(layer "F.Fab")
		)
		(fp_line
			(start -2.500122 2.500122)
			(end -2.500122 -2.500122)
			(stroke
				(width 0.1)
				(type default)
			)
			(layer "F.Fab")
		)
		(fp_line
			(start 2.500122 2.500122)
			(end -2.500122 2.500122)
			(stroke
				(width 0.1)
				(type default)
			)
			(layer "F.Fab")
		)
		(fp_line
			(start -3.6576 1.8034)
			(end -2.8956 1.8034)
			(stroke
				(width 0.1)
				(type default)
			)
			(layer "F.Fab")
		)
		(fp_line
			(start 2.8829 0.2032)
			(end 3.2639 0.2032)
			(stroke
				(width 0.1)
				(type default)
			)
			(layer "F.Fab")
		)
		(fp_line
			(start -3.2639 -0.1778)
			(end -2.8829 -0.1778)
			(stroke
				(width 0.1)
				(type default)
			)
			(layer "F.Fab")
		)
		(fp_line
			(start 2.8702 -1.778)
			(end 3.6322 -1.778)
			(stroke
				(width 0.1)
				(type default)
			)
			(layer "F.Fab")
		)
		(fp_line
			(start -2.500122 -2.500122)
			(end 2.500122 -2.500122)
			(stroke
				(width 0.1)
				(type default)
			)
			(layer "F.Fab")
		)
		(fp_line
			(start 2.500122 -2.500122)
			(end 2.500122 2.500122)
			(stroke
				(width 0.1)
				(type default)
			)
			(layer "F.Fab")
		)
		(fp_line
			(start -1.8034 -2.8702)
			(end -1.8034 -3.6322)
			(stroke
				(width 0.1)
				(type default)
			)
			(layer "F.Fab")
		)
		(fp_line
			(start 0.1778 -3.2385)
			(end 0.1778 -2.8575)
			(stroke
				(width 0.1)
				(type default)
			)
			(layer "F.Fab")
		)
		(fp_poly
			(pts
				(xy -2.921 -1.800098) (xy -3.504184 -1.508506) (xy -3.504184 -2.09169)
			)
			(stroke
				(width 0)
				(type default)
			)
			(fill yes)
			(layer "F.Fab")
		)
		(fp_text user "11"
			(at -4.411726 4.152646 0)
			(unlocked yes)
			(layer "F.SilkS")
			(effects
				(font
					(size 0.635 0.4064)
					(thickness 0.1524)
				)
				(justify left)
			)
		)
		(fp_text user "10"
			(at -4.704334 2.981706 0)
			(unlocked yes)
			(layer "F.SilkS")
			(effects
				(font
					(size 0.635 0.4064)
					(thickness 0.1524)
				)
				(justify left)
			)
		)
		(fp_text user "20"
			(at 3.403854 2.908046 0)
			(unlocked yes)
			(layer "F.SilkS")
			(effects
				(font
					(size 0.635 0.4064)
					(thickness 0.1524)
				)
				(justify left)
			)
		)
		(fp_text user "21"
			(at 4.510786 2.796286 0)
			(unlocked yes)
			(layer "F.SilkS")
			(effects
				(font
					(size 0.635 0.4064)
					(thickness 0.1524)
				)
				(justify left)
			)
		)
		(fp_text user "30"
			(at 4.480306 -1.526794 0)
			(unlocked yes)
			(layer "F.SilkS")
			(effects
				(font
					(size 0.635 0.4064)
					(thickness 0.1524)
				)
				(justify left)
			)
		)
		(fp_text user "31"
			(at 3.184906 -2.288794 0)
			(unlocked yes)
			(layer "F.SilkS")
			(effects
				(font
					(size 0.635 0.4064)
					(thickness 0.1524)
				)
				(justify left)
			)
		)
		(fp_text user "40"
			(at -4.485894 -5.463794 0)
			(unlocked yes)
			(layer "F.SilkS")
			(effects
				(font
					(size 0.635 0.4064)
					(thickness 0.1524)
				)
				(justify left)
			)
		)
		(fp_text user "11"
			(at -2.8702 3.278632 270)
			(unlocked yes)
			(layer "F.Fab")
			(effects
				(font
					(size 0.635 0.4064)
					(thickness 0.1524)
				)
				(justify left)
			)
		)
		(fp_text user "20"
			(at 2.0828 3.253232 270)
			(unlocked yes)
			(layer "F.Fab")
			(effects
				(font
					(size 0.635 0.4064)
					(thickness 0.1524)
				)
				(justify left)
			)
		)
		(fp_text user "10"
			(at -3.253232 2.1336 180)
			(unlocked yes)
			(layer "F.Fab")
			(effects
				(font
					(size 0.635 0.4064)
					(thickness 0.1524)
				)
				(justify left)
			)
		)
		(fp_text user "21"
			(at 3.274568 1.8796 180)
			(unlocked yes)
			(layer "F.Fab")
			(effects
				(font
					(size 0.635 0.4064)
					(thickness 0.1524)
				)
				(justify left)
			)
		)
		(fp_text user "40"
			(at -3.2004 -3.096768 270)
			(unlocked yes)
			(layer "F.Fab")
			(effects
				(font
					(size 0.635 0.4064)
					(thickness 0.1524)
				)
				(justify left)
			)
		)
		(fp_text user "30"
			(at 3.223768 -3.0988 180)
			(unlocked yes)
			(layer "F.Fab")
			(effects
				(font
					(size 0.635 0.4064)
					(thickness 0.1524)
				)
				(justify left)
			)
		)
		(fp_text user "31"
			(at 1.8542 -3.172968 270)
			(unlocked yes)
			(layer "F.Fab")
			(effects
				(font
					(size 0.635 0.4064)
					(thickness 0.1524)
				)
				(justify left)
			)
		)
		(pad "1" smd rect
			(at -2.400046 -1.800098 180)
			(size 0.1778 0.6096)
			(layers "F.Cu" "F.Mask" "F.Paste")
			(net "NC_PVCCD_HV_CPU1_APWM8")
		)
		(pad "2" smd rect
			(at -2.400046 -1.400048 180)
			(size 0.1778 0.6096)
			(layers "F.Cu" "F.Mask" "F.Paste")
			(net "NC_PVCCD_HV_CPU1_APWM7")
		)
		(pad "3" smd rect
			(at -2.400046 -0.999998 180)
			(size 0.1778 0.6096)
			(layers "F.Cu" "F.Mask" "F.Paste")
			(net "NC_PVCCD_HV_CPU1_APWM6")
		)
		(pad "4" smd rect
			(at -2.400046 -0.599948 180)
			(size 0.1778 0.6096)
			(layers "F.Cu" "F.Mask" "F.Paste")
			(net "NC_PVCCD_HV_CPU1_APWM5")
		)
		(pad "5" smd rect
			(at -2.400046 -0.199898 180)
			(size 0.1778 0.6096)
			(layers "F.Cu" "F.Mask" "F.Paste")
			(net "NC_PVCCD_HV_CPU1_APWM4")
		)
		(pad "6" smd rect
			(at -2.400046 0.199898 180)
			(size 0.1778 0.6096)
			(layers "F.Cu" "F.Mask" "F.Paste")
			(net "NC_PVCCD_HV_CPU1_APWM3")
		)
		(pad "7" smd rect
			(at -2.400046 0.599948 180)
			(size 0.1778 0.6096)
			(layers "F.Cu" "F.Mask" "F.Paste")
			(net "NC_PVCCD_HV_CPU1_APWM2")
		)
		(pad "8" smd rect
			(at -2.400046 0.999998 180)
			(size 0.1778 0.6096)
			(layers "F.Cu" "F.Mask" "F.Paste")
			(net "PVCCD_HV_CPU1_APWM1")
		)
		(pad "9" smd rect
			(at -2.400046 1.400048 180)
			(size 0.1778 0.6096)
			(layers "F.Cu" "F.Mask" "F.Paste")
			(net "SMB_DIO_PVCCD_HV_CPU1")
		)
		(pad "10" smd rect
			(at -2.400046 1.800098 180)
			(size 0.1778 0.6096)
			(layers "F.Cu" "F.Mask" "F.Paste")
			(net "SMB_CLK_PVCCD_HV_CPU1")
		)
		(pad "11" smd rect
			(at -1.800098 2.400046 270)
			(size 0.1778 0.6096)
			(layers "F.Cu" "F.Mask" "F.Paste")
			(net "NC_PVCCD_HV_CPU1_SMB_ALERT")
		)
		(pad "12" smd rect
			(at -1.400048 2.400046 270)
			(size 0.1778 0.6096)
			(layers "F.Cu" "F.Mask" "F.Paste")
			(net "PWRGD_PVCCD_HV_CPU1_R")
		)
		(pad "13" smd rect
			(at -0.999998 2.400046 270)
			(size 0.1778 0.6096)
			(layers "F.Cu" "F.Mask" "F.Paste")
			(net "PVCCD_HV_CPU1_EN_R")
		)
		(pad "14" smd rect
			(at -0.599948 2.400046 270)
			(size 0.1778 0.6096)
			(layers "F.Cu" "F.Mask" "F.Paste")
			(net "IRQ_PVCCD_CPU1_VRHOT_LVC3_R_N")
		)
		(pad "15" smd rect
			(at -0.199898 2.400046 270)
			(size 0.1778 0.6096)
			(layers "F.Cu" "F.Mask" "F.Paste")
			(net "PVCCD_HV_CPU1_PIN_ALT")
		)
		(pad "16" smd rect
			(at 0.199898 2.400046 270)
			(size 0.1778 0.6096)
			(layers "F.Cu" "F.Mask" "F.Paste")
			(net "NC_PVCCD_HV_CPU1_BVR_RDY")
		)
		(pad "17" smd rect
			(at 0.599948 2.400046 270)
			(size 0.1778 0.6096)
			(layers "F.Cu" "F.Mask" "F.Paste")
			(net "SVID_CLK_PVCCD_HV_CPU1_R")
		)
		(pad "18" smd rect
			(at 0.999998 2.400046 270)
			(size 0.1778 0.6096)
			(layers "F.Cu" "F.Mask" "F.Paste")
			(net "SVID_DIO_PVCCD_HV_CPU1_R")
		)
		(pad "19" smd rect
			(at 1.400048 2.400046 270)
			(size 0.1778 0.6096)
			(layers "F.Cu" "F.Mask" "F.Paste")
			(net "SVID_ALERT_PVCCD_HV_CPU1_R")
		)
		(pad "20" smd rect
			(at 1.800098 2.400046 270)
			(size 0.1778 0.6096)
			(layers "F.Cu" "F.Mask" "F.Paste")
			(net "GND")
		)
		(pad "21" smd rect
			(at 2.400046 1.800098 180)
			(size 0.1778 0.6096)
			(layers "F.Cu" "F.Mask" "F.Paste")
			(net "SH_PVCCD_HV_CPU1_R")
		)
		(pad "22" smd rect
			(at 2.400046 1.400048 180)
			(size 0.1778 0.6096)
			(layers "F.Cu" "F.Mask" "F.Paste")
			(net "VSENSE_PVCCD_HV_CPU1_DN")
		)
		(pad "23" smd rect
			(at 2.400046 0.999998 180)
			(size 0.1778 0.6096)
			(layers "F.Cu" "F.Mask" "F.Paste")
			(net "PVCCD_HV_CPU1_ACSP1")
		)
		(pad "24" smd rect
			(at 2.400046 0.599948 180)
			(size 0.1778 0.6096)
			(layers "F.Cu" "F.Mask" "F.Paste")
			(net "NC_PVCCD_HV_CPU1_ACSP2")
		)
		(pad "25" smd rect
			(at 2.400046 0.199898 180)
			(size 0.1778 0.6096)
			(layers "F.Cu" "F.Mask" "F.Paste")
			(net "NC_PVCCD_HV_CPU1_ACSP3")
		)
		(pad "26" smd rect
			(at 2.400046 -0.199898 180)
			(size 0.1778 0.6096)
			(layers "F.Cu" "F.Mask" "F.Paste")
			(net "NC_PVCCD_HV_CPU1_ACSP4")
		)
		(pad "27" smd rect
			(at 2.400046 -0.599948 180)
			(size 0.1778 0.6096)
			(layers "F.Cu" "F.Mask" "F.Paste")
			(net "NC_PVCCD_HV_CPU1_ACSP5")
		)
		(pad "28" smd rect
			(at 2.400046 -0.999998 180)
			(size 0.1778 0.6096)
			(layers "F.Cu" "F.Mask" "F.Paste")
			(net "NC_PVCCD_HV_CPU1_ACSP6")
		)
		(pad "29" smd rect
			(at 2.400046 -1.400048 180)
			(size 0.1778 0.6096)
			(layers "F.Cu" "F.Mask" "F.Paste")
			(net "NC_PVCCD_HV_CPU1_ACSP7")
		)
		(pad "30" smd rect
			(at 2.400046 -1.800098 180)
			(size 0.1778 0.6096)
			(layers "F.Cu" "F.Mask" "F.Paste")
			(net "NC_PVCCD_HV_CPU1_ACSP8")
		)
		(pad "31" smd rect
			(at 1.800098 -2.400046 270)
			(size 0.1778 0.6096)
			(layers "F.Cu" "F.Mask" "F.Paste")
			(net "GND")
		)
		(pad "32" smd rect
			(at 1.400048 -2.400046 270)
			(size 0.1778 0.6096)
			(layers "F.Cu" "F.Mask" "F.Paste")
			(net "GND")
		)
		(pad "33" smd rect
			(at 0.999998 -2.400046 270)
			(size 0.1778 0.6096)
			(layers "F.Cu" "F.Mask" "F.Paste")
			(net "PVCCD_HV_CPU1_FAULT")
		)
		(pad "34" smd rect
			(at 0.599948 -2.400046 270)
			(size 0.1778 0.6096)
			(layers "F.Cu" "F.Mask" "F.Paste")
			(net "PVCCD_HV_CPU1_ADDR")
		)
		(pad "35" smd rect
			(at 0.199898 -2.400046 270)
			(size 0.1778 0.6096)
			(layers "F.Cu" "F.Mask" "F.Paste")
			(net "PVCCD_HV_CPU1_ATSEN")
		)
		(pad "36" smd rect
			(at -0.199898 -2.400046 270)
			(size 0.1778 0.6096)
			(layers "F.Cu" "F.Mask" "F.Paste")
			(net "PVCCD_HV_CPU1_ISYS_R")
		)
		(pad "37" smd rect
			(at -0.599948 -2.400046 270)
			(size 0.1778 0.6096)
			(layers "F.Cu" "F.Mask" "F.Paste")
			(net "PVCCD_HV_CPU1_ISENSE_P")
		)
		(pad "38" smd rect
			(at -0.999998 -2.400046 270)
			(size 0.1778 0.6096)
			(layers "F.Cu" "F.Mask" "F.Paste")
			(net "PVCCD_HV_CPU1_ISENSE_N")
		)
		(pad "39" smd rect
			(at -1.400048 -2.400046 270)
			(size 0.1778 0.6096)
			(layers "F.Cu" "F.Mask" "F.Paste")
			(net "PVCCD_HV_CPU1_VCC")
		)
		(pad "40" smd rect
			(at -1.800098 -2.400046 270)
			(size 0.1778 0.6096)
			(layers "F.Cu" "F.Mask" "F.Paste")
			(net "PVCCD_HV_CPU1_VREF")
		)
		(pad "TH" smd rect
			(at 0 0 270)
			(size 3.6576 3.6576)
			(layers "F.Cu" "F.Mask" "F.Paste")
			(net "GND")
		)
		(zone
			(layer "F.Cu")
			(hatch none 0.5)
			(connect_pads
				(clearance 0)
			)
			(min_thickness 0.25)
			(keepout
				(tracks not_allowed)
				(vias allowed)
				(pads allowed)
				(copperpour not_allowed)
				(footprints allowed)
			)
			(placement
				(enabled no)
				(sheetname "")
			)
			(fill
				(thermal_gap 0.5)
				(thermal_bridge_width 0.5)
				(island_removal_mode 0)
			)
			(polygon
				(pts
					(xy 25.630886 -166.859204) (xy 29.517086 -166.859204) (xy 29.517086 -166.706804) (xy 25.783286 -166.706804)
					(xy 25.783286 -163.154868) (xy 25.630886 -163.154868)
				)
			)
		)
	)
	(footprint ""
		(layer "F.Cu")
		(at 342.14181 -338.298282 -90)
		(property "Reference" "PC1356"
			(at 0 0 270)
			(layer "F.SilkS")
			(hide yes)
			(effects
				(font
					(size 1.27 1.27)
				)
			)
		)
		(property "Value" ""
			(at 0 0 270)
			(layer "F.Fab")
			(effects
				(font
					(size 1.27 1.27)
				)
			)
		)
		(duplicate_pad_numbers_are_jumpers no)
		(fp_line
			(start -0.7874 0.4064)
			(end -0.7874 -0.4064)
			(stroke
				(width 0.1524)
				(type default)
			)
			(layer "F.SilkS")
		)
		(fp_line
			(start 0.7874 0.4064)
			(end -0.7874 0.4064)
			(stroke
				(width 0.1524)
				(type default)
			)
			(layer "F.SilkS")
		)
		(fp_line
			(start -0.7874 -0.4064)
			(end 0.7874 -0.4064)
			(stroke
				(width 0.1524)
				(type default)
			)
			(layer "F.SilkS")
		)
		(fp_line
			(start 0.7874 -0.4064)
			(end 0.7874 0.4064)
			(stroke
				(width 0.1524)
				(type default)
			)
			(layer "F.SilkS")
		)
		(fp_line
			(start -0.67945 0.3048)
			(end -0.67945 -0.305054)
			(stroke
				(width 0.1)
				(type default)
			)
			(layer "F.Fab")
		)
		(fp_line
			(start -0.12065 0.3048)
			(end -0.67945 0.3048)
			(stroke
				(width 0.1)
				(type default)
			)
			(layer "F.Fab")
		)
		(fp_line
			(start 0.120396 0.3048)
			(end 0.120396 0.2794)
			(stroke
				(width 0.1)
				(type default)
			)
			(layer "F.Fab")
		)
		(fp_line
			(start 0.67945 0.3048)
			(end 0.120396 0.3048)
			(stroke
				(width 0.1)
				(type default)
			)
			(layer "F.Fab")
		)
		(fp_line
			(start -0.12065 0.2794)
			(end -0.12065 0.3048)
			(stroke
				(width 0.1)
				(type default)
			)
			(layer "F.Fab")
		)
		(fp_line
			(start 0.120396 0.2794)
			(end -0.12065 0.2794)
			(stroke
				(width 0.1)
				(type default)
			)
			(layer "F.Fab")
		)
		(fp_line
			(start -0.12065 -0.2794)
			(end 0.12065 -0.2794)
			(stroke
				(width 0.1)
				(type default)
			)
			(layer "F.Fab")
		)
		(fp_line
			(start 0.12065 -0.2794)
			(end 0.12065 -0.3048)
			(stroke
				(width 0.1)
				(type default)
			)
			(layer "F.Fab")
		)
		(fp_line
			(start 0.12065 -0.3048)
			(end 0.67945 -0.3048)
			(stroke
				(width 0.1)
				(type default)
			)
			(layer "F.Fab")
		)
		(fp_line
			(start 0.67945 -0.3048)
			(end 0.67945 0.3048)
			(stroke
				(width 0.1)
				(type default)
			)
			(layer "F.Fab")
		)
		(fp_line
			(start -0.67945 -0.305054)
			(end -0.12065 -0.305054)
			(stroke
				(width 0.1)
				(type default)
			)
			(layer "F.Fab")
		)
		(fp_line
			(start -0.12065 -0.305054)
			(end -0.12065 -0.2794)
			(stroke
				(width 0.1)
				(type default)
			)
			(layer "F.Fab")
		)
		(pad "1" smd circle
			(at -0.40005 0 270)
			(size 0 0)
			(layers "F.Cu" "F.Mask" "F.Paste")
			(net "GND")
		)
		(pad "2" smd circle
			(at 0.40005 0 270)
			(size 0 0)
			(layers "F.Cu" "F.Mask" "F.Paste")
			(net "PVCCIN_CPU0_VREF")
		)
	)
)
